# T6G (Grand Teton) — schematic netlist excerpt (pin names and nets, part order shuffled) for the footprints in the layout excerpt that follows; sources: Cadence DE-HDL packaged netlist, KiCad conversion of 04192023_DAF0TMB3IC0_F0TG_MB_C_brd_V02_OCP.brd

C6119  Q_CAP  1PF 50V 0.05P COG  pkg C0402  page 179 : A = P1V2_CPU0_USB2_DVDD12 ; B = GND
PR415  Q_RES  0 5% CHIP  pkg 0402LF  page 224 : A = PVDD11_S3_P1_TEMP1 ; B = GND
C455  Q_CAP  1UF 4V 20% X6S  pkg 0201  page 356 : A = P0V9_CPU1_RT3_2A ; B = GND

(kicad_pcb
	(version 20260206)
	(generator "pcbnew")
	(generator_version "10.0")
	(general
		(thickness 1.6)
		(legacy_teardrops no)
	)
	(paper "A4")
	(title_block
		(title "04192023_DAF0TMB3IC0_F0TG_MB_C_brd_V02_OCP.brd")
		(comment 1 "Grand Teton / footprints 6618-6620 of 8354")
	)
	(layers
		(0 "F.Cu" signal "TOP")
		(4 "In1.Cu" signal "GND")
		(6 "In2.Cu" signal "IN1")
		(8 "In3.Cu" signal "GND1")
		(10 "In4.Cu" signal "IN2")
		(12 "In5.Cu" signal "GND2")
		(14 "In6.Cu" signal "IN3")
		(16 "In7.Cu" signal "GND3")
		(18 "In8.Cu" signal "VCC")
		(20 "In9.Cu" signal "VCC1")
		(22 "In10.Cu" signal "GND4")
		(24 "In11.Cu" signal "IN4")
		(26 "In12.Cu" signal "GND5")
		(28 "In13.Cu" signal "IN5")
		(30 "In14.Cu" signal "GND6")
		(32 "In15.Cu" signal "IN6")
		(34 "In16.Cu" signal "GND7")
		(2 "B.Cu" signal "BOTTOM")
		(9 "F.Adhes" user "F.Adhesive")
		(11 "B.Adhes" user "B.Adhesive")
		(13 "F.Paste" user "Package Geometry/Pastemask Top")
		(15 "B.Paste" user "Package Geometry/Pastemask Bottom")
		(5 "F.SilkS" user "Ref Des/Silkscreen Top")
		(7 "B.SilkS" user "Ref Des/Silkscreen Bottom")
		(1 "F.Mask" user "Board Geometry/Soldermask Top")
		(3 "B.Mask" user "Board Geometry/Soldermask Bottom")
		(17 "Dwgs.User" user "User.Drawings")
		(19 "Cmts.User" user "User.Comments")
		(21 "Eco1.User" user "User.Eco1")
		(23 "Eco2.User" user "User.Eco2")
		(25 "Edge.Cuts" user "Board Geometry/Outline")
		(27 "Margin" user)
		(31 "F.CrtYd" user "Package Geometry/Place Bound Top")
		(29 "B.CrtYd" user "Package Geometry/Place Bound Bottom")
		(35 "F.Fab" user "Ref Des/Assembly Top")
		(33 "B.Fab" user "Ref Des/Assembly Bottom")
	)
	(footprint ""
		(layer "B.Cu")
		(at 164.325554 -348.180406)
		(property "Reference" "PR415"
			(at 0 0 0)
			(layer "B.SilkS")
			(hide yes)
			(effects
				(font
					(size 1.27 1.27)
				)
				(justify mirror)
			)
		)
		(property "Value" ""
			(at 0 0 0)
			(layer "B.Fab")
			(effects
				(font
					(size 1.27 1.27)
				)
				(justify mirror)
			)
		)
		(duplicate_pad_numbers_are_jumpers no)
		(fp_line
			(start -0.7874 -0.4064)
			(end -0.7874 0.4064)
			(stroke
				(width 0.1524)
				(type default)
			)
			(layer "B.SilkS")
		)
		(fp_line
			(start -0.7874 0.4064)
			(end 0.7874 0.4064)
			(stroke
				(width 0.1524)
				(type default)
			)
			(layer "B.SilkS")
		)
		(fp_line
			(start 0.7874 -0.4064)
			(end -0.7874 -0.4064)
			(stroke
				(width 0.1524)
				(type default)
			)
			(layer "B.SilkS")
		)
		(fp_line
			(start 0.7874 0.4064)
			(end 0.7874 -0.4064)
			(stroke
				(width 0.1524)
				(type default)
			)
			(layer "B.SilkS")
		)
		(fp_line
			(start -0.67945 -0.3048)
			(end -0.67945 0.3048)
			(stroke
				(width 0.1)
				(type default)
			)
			(layer "B.Fab")
		)
		(fp_line
			(start -0.67945 0.3048)
			(end -0.120396 0.3048)
			(stroke
				(width 0.1)
				(type default)
			)
			(layer "B.Fab")
		)
		(fp_line
			(start -0.12065 -0.3048)
			(end -0.67945 -0.3048)
			(stroke
				(width 0.1)
				(type default)
			)
			(layer "B.Fab")
		)
		(fp_line
			(start -0.12065 -0.2794)
			(end -0.12065 -0.3048)
			(stroke
				(width 0.1)
				(type default)
			)
			(layer "B.Fab")
		)
		(fp_line
			(start -0.120396 0.2794)
			(end 0.12065 0.2794)
			(stroke
				(width 0.1)
				(type default)
			)
			(layer "B.Fab")
		)
		(fp_line
			(start -0.120396 0.3048)
			(end -0.120396 0.2794)
			(stroke
				(width 0.1)
				(type default)
			)
			(layer "B.Fab")
		)
		(fp_line
			(start 0.12065 -0.305054)
			(end 0.12065 -0.2794)
			(stroke
				(width 0.1)
				(type default)
			)
			(layer "B.Fab")
		)
		(fp_line
			(start 0.12065 -0.2794)
			(end -0.12065 -0.2794)
			(stroke
				(width 0.1)
				(type default)
			)
			(layer "B.Fab")
		)
		(fp_line
			(start 0.12065 0.2794)
			(end 0.12065 0.3048)
			(stroke
				(width 0.1)
				(type default)
			)
			(layer "B.Fab")
		)
		(fp_line
			(start 0.12065 0.3048)
			(end 0.67945 0.3048)
			(stroke
				(width 0.1)
				(type default)
			)
			(layer "B.Fab")
		)
		(fp_line
			(start 0.67945 -0.305054)
			(end 0.12065 -0.305054)
			(stroke
				(width 0.1)
				(type default)
			)
			(layer "B.Fab")
		)
		(fp_line
			(start 0.67945 0.3048)
			(end 0.67945 -0.305054)
			(stroke
				(width 0.1)
				(type default)
			)
			(layer "B.Fab")
		)
		(pad "1" smd circle
			(at 0.40005 0 180)
			(size 0 0)
			(layers "B.Cu" "B.Mask" "B.Paste")
			(net "PVDD11_S3_P1_TEMP1")
		)
		(pad "2" smd circle
			(at -0.40005 0 180)
			(size 0 0)
			(layers "B.Cu" "B.Mask" "B.Paste")
			(net "GND")
		)
	)
	(footprint ""
		(layer "B.Cu")
		(at 117.102128 -28.457906 180)
		(property "Reference" "C6119"
			(at 0 0 0)
			(layer "B.SilkS")
			(hide yes)
			(effects
				(font
					(size 1.27 1.27)
				)
				(justify mirror)
			)
		)
		(property "Value" ""
			(at 0 0 0)
			(layer "B.Fab")
			(effects
				(font
					(size 1.27 1.27)
				)
				(justify mirror)
			)
		)
		(duplicate_pad_numbers_are_jumpers no)
		(fp_line
			(start 0.7874 0.4064)
			(end 0.7874 -0.4064)
			(stroke
				(width 0.1524)
				(type default)
			)
			(layer "B.SilkS")
		)
		(fp_line
			(start 0.7874 -0.4064)
			(end -0.7874 -0.4064)
			(stroke
				(width 0.1524)
				(type default)
			)
			(layer "B.SilkS")
		)
		(fp_line
			(start -0.7874 0.4064)
			(end 0.7874 0.4064)
			(stroke
				(width 0.1524)
				(type default)
			)
			(layer "B.SilkS")
		)
		(fp_line
			(start -0.7874 -0.4064)
			(end -0.7874 0.4064)
			(stroke
				(width 0.1524)
				(type default)
			)
			(layer "B.SilkS")
		)
		(fp_line
			(start 0.67945 0.3048)
			(end 0.67945 -0.305054)
			(stroke
				(width 0.1)
				(type default)
			)
			(layer "B.Fab")
		)
		(fp_line
			(start 0.67945 -0.305054)
			(end 0.12065 -0.305054)
			(stroke
				(width 0.1)
				(type default)
			)
			(layer "B.Fab")
		)
		(fp_line
			(start 0.12065 0.3048)
			(end 0.67945 0.3048)
			(stroke
				(width 0.1)
				(type default)
			)
			(layer "B.Fab")
		)
		(fp_line
			(start 0.12065 0.2794)
			(end 0.12065 0.3048)
			(stroke
				(width 0.1)
				(type default)
			)
			(layer "B.Fab")
		)
		(fp_line
			(start 0.12065 -0.2794)
			(end -0.12065 -0.2794)
			(stroke
				(width 0.1)
				(type default)
			)
			(layer "B.Fab")
		)
		(fp_line
			(start 0.12065 -0.305054)
			(end 0.12065 -0.2794)
			(stroke
				(width 0.1)
				(type default)
			)
			(layer "B.Fab")
		)
		(fp_line
			(start -0.120396 0.3048)
			(end -0.120396 0.2794)
			(stroke
				(width 0.1)
				(type default)
			)
			(layer "B.Fab")
		)
		(fp_line
			(start -0.120396 0.2794)
			(end 0.12065 0.2794)
			(stroke
				(width 0.1)
				(type default)
			)
			(layer "B.Fab")
		)
		(fp_line
			(start -0.12065 -0.2794)
			(end -0.12065 -0.3048)
			(stroke
				(width 0.1)
				(type default)
			)
			(layer "B.Fab")
		)
		(fp_line
			(start -0.12065 -0.3048)
			(end -0.67945 -0.3048)
			(stroke
				(width 0.1)
				(type default)
			)
			(layer "B.Fab")
		)
		(fp_line
			(start -0.67945 0.3048)
			(end -0.120396 0.3048)
			(stroke
				(width 0.1)
				(type default)
			)
			(layer "B.Fab")
		)
		(fp_line
			(start -0.67945 -0.3048)
			(end -0.67945 0.3048)
			(stroke
				(width 0.1)
				(type default)
			)
			(layer "B.Fab")
		)
		(pad "1" smd circle
			(at 0.40005 0)
			(size 0 0)
			(layers "B.Cu" "B.Mask" "B.Paste")
			(net "P1V2_CPU0_USB2_DVDD12")
		)
		(pad "2" smd circle
			(at -0.40005 0)
			(size 0 0)
			(layers "B.Cu" "B.Mask" "B.Paste")
			(net "GND")
		)
	)
	(footprint ""
		(layer "B.Cu")
		(at 114.478562 -386.766562 90)
		(property "Reference" "C455"
			(at 0 0 90)
			(layer "B.SilkS")
			(hide yes)
			(effects
				(font
					(size 1.27 1.27)
				)
				(justify mirror)
			)
		)
		(property "Value" ""
			(at 0 0 90)
			(layer "B.Fab")
			(effects
				(font
					(size 1.27 1.27)
				)
				(justify mirror)
			)
		)
		(duplicate_pad_numbers_are_jumpers no)
		(fp_line
			(start 0.299974 -0.150114)
			(end -0.299974 -0.150114)
			(stroke
				(width 0.1)
				(type default)
			)
			(layer "B.Fab")
		)
		(fp_line
			(start -0.299974 -0.150114)
			(end -0.299974 0.150114)
			(stroke
				(width 0.1)
				(type default)
			)
			(layer "B.Fab")
		)
		(fp_line
			(start 0.299974 0.150114)
			(end 0.299974 -0.150114)
			(stroke
				(width 0.1)
				(type default)
			)
			(layer "B.Fab")
		)
		(fp_line
			(start -0.299974 0.150114)
			(end 0.299974 0.150114)
			(stroke
				(width 0.1)
				(type default)
			)
			(layer "B.Fab")
		)
		(pad "1" smd rect
			(at 0.2667 0 270)
			(size 0.3048 0.381)
			(layers "B.Cu" "B.Mask" "B.Paste")
			(net "P0V9_CPU1_RT3_2A")
		)
		(pad "2" smd rect
			(at -0.2667 0 270)
			(size 0.3048 0.381)
			(layers "B.Cu" "B.Mask" "B.Paste")
			(net "GND")
		)
	)
)
